(kicad_pcb
	(version 20260206)
	(generator "pcbnew")
	(generator_version "10.0")
	(general
		(thickness 1.6)
		(legacy_teardrops no)
	)
	(paper "A4")
	(title_block
		(title "01162023_DA0F0TEBIF0_F0T_Expander_BD_F_brd_V02_OCP.brd")
		(comment 1 "Grand Teton / footprints 1303-1309 of 9728")
	)
	(layers
		(0 "F.Cu" signal "TOP")
		(4 "In1.Cu" signal "GND")
		(6 "In2.Cu" signal "VCC")
		(8 "In3.Cu" signal "VCC1")
		(10 "In4.Cu" signal "GND1")
		(12 "In5.Cu" signal "IN1")
		(14 "In6.Cu" signal "GND2")
		(16 "In7.Cu" signal "IN2")
		(18 "In8.Cu" signal "GND3")
		(20 "In9.Cu" signal "IN3")
		(22 "In10.Cu" signal "GND4")
		(24 "In11.Cu" signal "IN4")
		(26 "In12.Cu" signal "GND5")
		(28 "In13.Cu" signal "IN5")
		(30 "In14.Cu" signal "GND6")
		(32 "In15.Cu" signal "IN6")
		(34 "In16.Cu" signal "GND7")
		(2 "B.Cu" signal "BOTTOM")
		(9 "F.Adhes" user "F.Adhesive")
		(11 "B.Adhes" user "B.Adhesive")
		(13 "F.Paste" user "Package Geometry/Pastemask Top")
		(15 "B.Paste" user "Package Geometry/Pastemask Bottom")
		(5 "F.SilkS" user "Ref Des/Silkscreen Top")
		(7 "B.SilkS" user "Ref Des/Silkscreen Bottom")
		(1 "F.Mask" user "Board Geometry/Soldermask Top")
		(3 "B.Mask" user "Board Geometry/Soldermask Bottom")
		(17 "Dwgs.User" user "User.Drawings")
		(19 "Cmts.User" user "User.Comments")
		(21 "Eco1.User" user "User.Eco1")
		(23 "Eco2.User" user "User.Eco2")
		(25 "Edge.Cuts" user "Board Geometry/Outline")
		(27 "Margin" user)
		(31 "F.CrtYd" user "Package Geometry/Place Bound Top")
		(29 "B.CrtYd" user "Package Geometry/Place Bound Bottom")
		(35 "F.Fab" user "Ref Des/Assembly Top")
		(33 "B.Fab" user "Ref Des/Assembly Bottom")
	)
	(footprint ""
		(layer "F.Cu")
		(at 80.915002 -356.244906 90)
		(property "Reference" "C148"
			(at 0 0 90)
			(layer "F.SilkS")
			(hide yes)
			(effects
				(font
					(size 1.27 1.27)
				)
			)
		)
		(property "Value" ""
			(at 0 0 90)
			(layer "F.Fab")
			(effects
				(font
					(size 1.27 1.27)
				)
			)
		)
		(duplicate_pad_numbers_are_jumpers no)
		(fp_line
			(start 0.299974 -0.150114)
			(end 0.299974 0.150114)
			(stroke
				(width 0.1)
				(type default)
			)
			(layer "F.Fab")
		)
		(fp_line
			(start -0.299974 -0.150114)
			(end 0.299974 -0.150114)
			(stroke
				(width 0.1)
				(type default)
			)
			(layer "F.Fab")
		)
		(fp_line
			(start 0.299974 0.150114)
			(end -0.299974 0.150114)
			(stroke
				(width 0.1)
				(type default)
			)
			(layer "F.Fab")
		)
		(fp_line
			(start -0.299974 0.150114)
			(end -0.299974 -0.150114)
			(stroke
				(width 0.1)
				(type default)
			)
			(layer "F.Fab")
		)
		(pad "1" smd rect
			(at -0.2667 0 90)
			(size 0.3048 0.381)
			(layers "F.Cu" "F.Mask" "F.Paste")
			(net "P5E_PEX0_STN6_TX_DN<102>")
		)
		(pad "2" smd rect
			(at 0.2667 0 90)
			(size 0.3048 0.381)
			(layers "F.Cu" "F.Mask" "F.Paste")
			(net "P5E_PEX0_STN6_TX_C_DN<102>")
		)
	)
	(footprint ""
		(layer "F.Cu")
		(at 331.06614 -95.263716 -90)
		(property "Reference" "PC324"
			(at 0 0 270)
			(layer "F.SilkS")
			(hide yes)
			(effects
				(font
					(size 1.27 1.27)
				)
			)
		)
		(property "Value" ""
			(at 0 0 270)
			(layer "F.Fab")
			(effects
				(font
					(size 1.27 1.27)
				)
			)
		)
		(duplicate_pad_numbers_are_jumpers no)
		(fp_line
			(start -0.7874 0.4064)
			(end -0.7874 -0.4064)
			(stroke
				(width 0.1524)
				(type default)
			)
			(layer "F.SilkS")
		)
		(fp_line
			(start 0.7874 0.4064)
			(end -0.7874 0.4064)
			(stroke
				(width 0.1524)
				(type default)
			)
			(layer "F.SilkS")
		)
		(fp_line
			(start -0.7874 -0.4064)
			(end 0.7874 -0.4064)
			(stroke
				(width 0.1524)
				(type default)
			)
			(layer "F.SilkS")
		)
		(fp_line
			(start 0.7874 -0.4064)
			(end 0.7874 0.4064)
			(stroke
				(width 0.1524)
				(type default)
			)
			(layer "F.SilkS")
		)
		(fp_line
			(start -0.67945 0.3048)
			(end -0.67945 -0.305054)
			(stroke
				(width 0.1)
				(type default)
			)
			(layer "F.Fab")
		)
		(fp_line
			(start -0.12065 0.3048)
			(end -0.67945 0.3048)
			(stroke
				(width 0.1)
				(type default)
			)
			(layer "F.Fab")
		)
		(fp_line
			(start 0.120396 0.3048)
			(end 0.120396 0.2794)
			(stroke
				(width 0.1)
				(type default)
			)
			(layer "F.Fab")
		)
		(fp_line
			(start 0.67945 0.3048)
			(end 0.120396 0.3048)
			(stroke
				(width 0.1)
				(type default)
			)
			(layer "F.Fab")
		)
		(fp_line
			(start -0.12065 0.2794)
			(end -0.12065 0.3048)
			(stroke
				(width 0.1)
				(type default)
			)
			(layer "F.Fab")
		)
		(fp_line
			(start 0.120396 0.2794)
			(end -0.12065 0.2794)
			(stroke
				(width 0.1)
				(type default)
			)
			(layer "F.Fab")
		)
		(fp_line
			(start -0.12065 -0.2794)
			(end 0.12065 -0.2794)
			(stroke
				(width 0.1)
				(type default)
			)
			(layer "F.Fab")
		)
		(fp_line
			(start 0.12065 -0.2794)
			(end 0.12065 -0.3048)
			(stroke
				(width 0.1)
				(type default)
			)
			(layer "F.Fab")
		)
		(fp_line
			(start 0.12065 -0.3048)
			(end 0.67945 -0.3048)
			(stroke
				(width 0.1)
				(type default)
			)
			(layer "F.Fab")
		)
		(fp_line
			(start 0.67945 -0.3048)
			(end 0.67945 0.3048)
			(stroke
				(width 0.1)
				(type default)
			)
			(layer "F.Fab")
		)
		(fp_line
			(start -0.67945 -0.305054)
			(end -0.12065 -0.305054)
			(stroke
				(width 0.1)
				(type default)
			)
			(layer "F.Fab")
		)
		(fp_line
			(start -0.12065 -0.305054)
			(end -0.12065 -0.2794)
			(stroke
				(width 0.1)
				(type default)
			)
			(layer "F.Fab")
		)
		(pad "1" smd circle
			(at -0.40005 0 270)
			(size 0 0)
			(layers "F.Cu" "F.Mask" "F.Paste")
			(net "P5V_AUX")
		)
		(pad "2" smd circle
			(at 0.40005 0 270)
			(size 0 0)
			(layers "F.Cu" "F.Mask" "F.Paste")
			(net "GND")
		)
	)
	(footprint ""
		(layer "F.Cu")
		(at 58.709052 -26.03373)
		(property "Reference" "R4056"
			(at 0 0 0)
			(layer "F.SilkS")
			(hide yes)
			(effects
				(font
					(size 1.27 1.27)
				)
			)
		)
		(property "Value" ""
			(at 0 0 0)
			(layer "F.Fab")
			(effects
				(font
					(size 1.27 1.27)
				)
			)
		)
		(duplicate_pad_numbers_are_jumpers no)
		(fp_line
			(start -0.7874 -0.4064)
			(end 0.7874 -0.4064)
			(stroke
				(width 0.1524)
				(type default)
			)
			(layer "F.SilkS")
		)
		(fp_line
			(start -0.7874 0.4064)
			(end -0.7874 -0.4064)
			(stroke
				(width 0.1524)
				(type default)
			)
			(layer "F.SilkS")
		)
		(fp_line
			(start 0.7874 -0.4064)
			(end 0.7874 0.4064)
			(stroke
				(width 0.1524)
				(type default)
			)
			(layer "F.SilkS")
		)
		(fp_line
			(start 0.7874 0.4064)
			(end -0.7874 0.4064)
			(stroke
				(width 0.1524)
				(type default)
			)
			(layer "F.SilkS")
		)
		(fp_line
			(start -0.67945 -0.305054)
			(end -0.12065 -0.305054)
			(stroke
				(width 0.1)
				(type default)
			)
			(layer "F.Fab")
		)
		(fp_line
			(start -0.67945 0.3048)
			(end -0.67945 -0.305054)
			(stroke
				(width 0.1)
				(type default)
			)
			(layer "F.Fab")
		)
		(fp_line
			(start -0.12065 -0.305054)
			(end -0.12065 -0.2794)
			(stroke
				(width 0.1)
				(type default)
			)
			(layer "F.Fab")
		)
		(fp_line
			(start -0.12065 -0.2794)
			(end 0.12065 -0.2794)
			(stroke
				(width 0.1)
				(type default)
			)
			(layer "F.Fab")
		)
		(fp_line
			(start -0.12065 0.2794)
			(end -0.12065 0.3048)
			(stroke
				(width 0.1)
				(type default)
			)
			(layer "F.Fab")
		)
		(fp_line
			(start -0.12065 0.3048)
			(end -0.67945 0.3048)
			(stroke
				(width 0.1)
				(type default)
			)
			(layer "F.Fab")
		)
		(fp_line
			(start 0.120396 0.2794)
			(end -0.12065 0.2794)
			(stroke
				(width 0.1)
				(type default)
			)
			(layer "F.Fab")
		)
		(fp_line
			(start 0.120396 0.3048)
			(end 0.120396 0.2794)
			(stroke
				(width 0.1)
				(type default)
			)
			(layer "F.Fab")
		)
		(fp_line
			(start 0.12065 -0.3048)
			(end 0.67945 -0.3048)
			(stroke
				(width 0.1)
				(type default)
			)
			(layer "F.Fab")
		)
		(fp_line
			(start 0.12065 -0.2794)
			(end 0.12065 -0.3048)
			(stroke
				(width 0.1)
				(type default)
			)
			(layer "F.Fab")
		)
		(fp_line
			(start 0.67945 -0.3048)
			(end 0.67945 0.3048)
			(stroke
				(width 0.1)
				(type default)
			)
			(layer "F.Fab")
		)
		(fp_line
			(start 0.67945 0.3048)
			(end 0.120396 0.3048)
			(stroke
				(width 0.1)
				(type default)
			)
			(layer "F.Fab")
		)
		(pad "1" smd circle
			(at -0.40005 0)
			(size 0 0)
			(layers "F.Cu" "F.Mask" "F.Paste")
			(net "P3V3_AUX")
		)
		(pad "2" smd circle
			(at 0.40005 0)
			(size 0 0)
			(layers "F.Cu" "F.Mask" "F.Paste")
			(net "PRSNT_SSD2_R_N")
		)
	)
	(footprint ""
		(layer "F.Cu")
		(at 41.984168 -350.098614 90)
		(property "Reference" "C2173"
			(at 0 0 90)
			(layer "F.SilkS")
			(hide yes)
			(effects
				(font
					(size 1.27 1.27)
				)
			)
		)
		(property "Value" ""
			(at 0 0 90)
			(layer "F.Fab")
			(effects
				(font
					(size 1.27 1.27)
				)
			)
		)
		(duplicate_pad_numbers_are_jumpers no)
		(fp_line
			(start 0.299974 -0.150114)
			(end 0.299974 0.150114)
			(stroke
				(width 0.1)
				(type default)
			)
			(layer "F.Fab")
		)
		(fp_line
			(start -0.299974 -0.150114)
			(end 0.299974 -0.150114)
			(stroke
				(width 0.1)
				(type default)
			)
			(layer "F.Fab")
		)
		(fp_line
			(start 0.299974 0.150114)
			(end -0.299974 0.150114)
			(stroke
				(width 0.1)
				(type default)
			)
			(layer "F.Fab")
		)
		(fp_line
			(start -0.299974 0.150114)
			(end -0.299974 -0.150114)
			(stroke
				(width 0.1)
				(type default)
			)
			(layer "F.Fab")
		)
		(pad "1" smd rect
			(at -0.2667 0 90)
			(size 0.3048 0.381)
			(layers "F.Cu" "F.Mask" "F.Paste")
			(net "P5E_PEX0_STN4_TX_DN<69>")
		)
		(pad "2" smd rect
			(at 0.2667 0 90)
			(size 0.3048 0.381)
			(layers "F.Cu" "F.Mask" "F.Paste")
			(net "P5E_PEX0_STN4_TX_C_DN<69>")
		)
	)
	(footprint ""
		(layer "F.Cu")
		(at 219.202 -195.072 180)
		(property "Reference" "C2705"
			(at 0 0 180)
			(layer "F.SilkS")
			(hide yes)
			(effects
				(font
					(size 1.27 1.27)
				)
			)
		)
		(property "Value" ""
			(at 0 0 180)
			(layer "F.Fab")
			(effects
				(font
					(size 1.27 1.27)
				)
			)
		)
		(duplicate_pad_numbers_are_jumpers no)
		(fp_line
			(start 0.7874 0.4064)
			(end -0.7874 0.4064)
			(stroke
				(width 0.1524)
				(type default)
			)
			(layer "F.SilkS")
		)
		(fp_line
			(start 0.7874 -0.4064)
			(end 0.7874 0.4064)
			(stroke
				(width 0.1524)
				(type default)
			)
			(layer "F.SilkS")
		)
		(fp_line
			(start -0.7874 0.4064)
			(end -0.7874 -0.4064)
			(stroke
				(width 0.1524)
				(type default)
			)
			(layer "F.SilkS")
		)
		(fp_line
			(start -0.7874 -0.4064)
			(end 0.7874 -0.4064)
			(stroke
				(width 0.1524)
				(type default)
			)
			(layer "F.SilkS")
		)
		(fp_line
			(start 0.67945 0.3048)
			(end 0.120396 0.3048)
			(stroke
				(width 0.1)
				(type default)
			)
			(layer "F.Fab")
		)
		(fp_line
			(start 0.67945 -0.3048)
			(end 0.67945 0.3048)
			(stroke
				(width 0.1)
				(type default)
			)
			(layer "F.Fab")
		)
		(fp_line
			(start 0.12065 -0.2794)
			(end 0.12065 -0.3048)
			(stroke
				(width 0.1)
				(type default)
			)
			(layer "F.Fab")
		)
		(fp_line
			(start 0.12065 -0.3048)
			(end 0.67945 -0.3048)
			(stroke
				(width 0.1)
				(type default)
			)
			(layer "F.Fab")
		)
		(fp_line
			(start 0.120396 0.3048)
			(end 0.120396 0.2794)
			(stroke
				(width 0.1)
				(type default)
			)
			(layer "F.Fab")
		)
		(fp_line
			(start 0.120396 0.2794)
			(end -0.12065 0.2794)
			(stroke
				(width 0.1)
				(type default)
			)
			(layer "F.Fab")
		)
		(fp_line
			(start -0.12065 0.3048)
			(end -0.67945 0.3048)
			(stroke
				(width 0.1)
				(type default)
			)
			(layer "F.Fab")
		)
		(fp_line
			(start -0.12065 0.2794)
			(end -0.12065 0.3048)
			(stroke
				(width 0.1)
				(type default)
			)
			(layer "F.Fab")
		)
		(fp_line
			(start -0.12065 -0.2794)
			(end 0.12065 -0.2794)
			(stroke
				(width 0.1)
				(type default)
			)
			(layer "F.Fab")
		)
		(fp_line
			(start -0.12065 -0.305054)
			(end -0.12065 -0.2794)
			(stroke
				(width 0.1)
				(type default)
			)
			(layer "F.Fab")
		)
		(fp_line
			(start -0.67945 0.3048)
			(end -0.67945 -0.305054)
			(stroke
				(width 0.1)
				(type default)
			)
			(layer "F.Fab")
		)
		(fp_line
			(start -0.67945 -0.305054)
			(end -0.12065 -0.305054)
			(stroke
				(width 0.1)
				(type default)
			)
			(layer "F.Fab")
		)
		(pad "1" smd circle
			(at -0.40005 0 180)
			(size 0 0)
			(layers "F.Cu" "F.Mask" "F.Paste")
			(net "GND")
		)
		(pad "2" smd circle
			(at 0.40005 0 180)
			(size 0 0)
			(layers "F.Cu" "F.Mask" "F.Paste")
			(net "P3V3_NIC7")
		)
	)
	(footprint ""
		(layer "F.Cu")
		(at 206.623158 -83.659472)
		(property "Reference" "R4303"
			(at 0 0 0)
			(layer "F.SilkS")
			(hide yes)
			(effects
				(font
					(size 1.27 1.27)
				)
			)
		)
		(property "Value" ""
			(at 0 0 0)
			(layer "F.Fab")
			(effects
				(font
					(size 1.27 1.27)
				)
			)
		)
		(duplicate_pad_numbers_are_jumpers no)
		(fp_line
			(start -0.7874 -0.4064)
			(end 0.7874 -0.4064)
			(stroke
				(width 0.1524)
				(type default)
			)
			(layer "F.SilkS")
		)
		(fp_line
			(start -0.7874 0.4064)
			(end -0.7874 -0.4064)
			(stroke
				(width 0.1524)
				(type default)
			)
			(layer "F.SilkS")
		)
		(fp_line
			(start 0.7874 -0.4064)
			(end 0.7874 0.4064)
			(stroke
				(width 0.1524)
				(type default)
			)
			(layer "F.SilkS")
		)
		(fp_line
			(start 0.7874 0.4064)
			(end -0.7874 0.4064)
			(stroke
				(width 0.1524)
				(type default)
			)
			(layer "F.SilkS")
		)
		(fp_line
			(start -0.67945 -0.305054)
			(end -0.12065 -0.305054)
			(stroke
				(width 0.1)
				(type default)
			)
			(layer "F.Fab")
		)
		(fp_line
			(start -0.67945 0.3048)
			(end -0.67945 -0.305054)
			(stroke
				(width 0.1)
				(type default)
			)
			(layer "F.Fab")
		)
		(fp_line
			(start -0.12065 -0.305054)
			(end -0.12065 -0.2794)
			(stroke
				(width 0.1)
				(type default)
			)
			(layer "F.Fab")
		)
		(fp_line
			(start -0.12065 -0.2794)
			(end 0.12065 -0.2794)
			(stroke
				(width 0.1)
				(type default)
			)
			(layer "F.Fab")
		)
		(fp_line
			(start -0.12065 0.2794)
			(end -0.12065 0.3048)
			(stroke
				(width 0.1)
				(type default)
			)
			(layer "F.Fab")
		)
		(fp_line
			(start -0.12065 0.3048)
			(end -0.67945 0.3048)
			(stroke
				(width 0.1)
				(type default)
			)
			(layer "F.Fab")
		)
		(fp_line
			(start 0.120396 0.2794)
			(end -0.12065 0.2794)
			(stroke
				(width 0.1)
				(type default)
			)
			(layer "F.Fab")
		)
		(fp_line
			(start 0.120396 0.3048)
			(end 0.120396 0.2794)
			(stroke
				(width 0.1)
				(type default)
			)
			(layer "F.Fab")
		)
		(fp_line
			(start 0.12065 -0.3048)
			(end 0.67945 -0.3048)
			(stroke
				(width 0.1)
				(type default)
			)
			(layer "F.Fab")
		)
		(fp_line
			(start 0.12065 -0.2794)
			(end 0.12065 -0.3048)
			(stroke
				(width 0.1)
				(type default)
			)
			(layer "F.Fab")
		)
		(fp_line
			(start 0.67945 -0.3048)
			(end 0.67945 0.3048)
			(stroke
				(width 0.1)
				(type default)
			)
			(layer "F.Fab")
		)
		(fp_line
			(start 0.67945 0.3048)
			(end 0.120396 0.3048)
			(stroke
				(width 0.1)
				(type default)
			)
			(layer "F.Fab")
		)
		(pad "1" smd circle
			(at -0.40005 0)
			(size 0 0)
			(layers "F.Cu" "F.Mask" "F.Paste")
			(net "SSD1_LED_R")
		)
		(pad "2" smd circle
			(at 0.40005 0)
			(size 0 0)
			(layers "F.Cu" "F.Mask" "F.Paste")
			(net "SSD1_LED")
		)
	)
	(footprint ""
		(layer "F.Cu")
		(at 448.18554 -25.1587 -90)
		(property "Reference" "R5750"
			(at 0 0 270)
			(layer "F.SilkS")
			(hide yes)
			(effects
				(font
					(size 1.27 1.27)
				)
			)
		)
		(property "Value" ""
			(at 0 0 270)
			(layer "F.Fab")
			(effects
				(font
					(size 1.27 1.27)
				)
			)
		)
		(duplicate_pad_numbers_are_jumpers no)
		(fp_line
			(start -0.7874 0.4064)
			(end -0.7874 -0.4064)
			(stroke
				(width 0.1524)
				(type default)
			)
			(layer "F.SilkS")
		)
		(fp_line
			(start 0.7874 0.4064)
			(end -0.7874 0.4064)
			(stroke
				(width 0.1524)
				(type default)
			)
			(layer "F.SilkS")
		)
		(fp_line
			(start -0.7874 -0.4064)
			(end 0.7874 -0.4064)
			(stroke
				(width 0.1524)
				(type default)
			)
			(layer "F.SilkS")
		)
		(fp_line
			(start 0.7874 -0.4064)
			(end 0.7874 0.4064)
			(stroke
				(width 0.1524)
				(type default)
			)
			(layer "F.SilkS")
		)
		(fp_line
			(start -0.67945 0.3048)
			(end -0.67945 -0.305054)
			(stroke
				(width 0.1)
				(type default)
			)
			(layer "F.Fab")
		)
		(fp_line
			(start -0.12065 0.3048)
			(end -0.67945 0.3048)
			(stroke
				(width 0.1)
				(type default)
			)
			(layer "F.Fab")
		)
		(fp_line
			(start 0.120396 0.3048)
			(end 0.120396 0.2794)
			(stroke
				(width 0.1)
				(type default)
			)
			(layer "F.Fab")
		)
		(fp_line
			(start 0.67945 0.3048)
			(end 0.120396 0.3048)
			(stroke
				(width 0.1)
				(type default)
			)
			(layer "F.Fab")
		)
		(fp_line
			(start -0.12065 0.2794)
			(end -0.12065 0.3048)
			(stroke
				(width 0.1)
				(type default)
			)
			(layer "F.Fab")
		)
		(fp_line
			(start 0.120396 0.2794)
			(end -0.12065 0.2794)
			(stroke
				(width 0.1)
				(type default)
			)
			(layer "F.Fab")
		)
		(fp_line
			(start -0.12065 -0.2794)
			(end 0.12065 -0.2794)
			(stroke
				(width 0.1)
				(type default)
			)
			(layer "F.Fab")
		)
		(fp_line
			(start 0.12065 -0.2794)
			(end 0.12065 -0.3048)
			(stroke
				(width 0.1)
				(type default)
			)
			(layer "F.Fab")
		)
		(fp_line
			(start 0.12065 -0.3048)
			(end 0.67945 -0.3048)
			(stroke
				(width 0.1)
				(type default)
			)
			(layer "F.Fab")
		)
		(fp_line
			(start 0.67945 -0.3048)
			(end 0.67945 0.3048)
			(stroke
				(width 0.1)
				(type default)
			)
			(layer "F.Fab")
		)
		(fp_line
			(start -0.67945 -0.305054)
			(end -0.12065 -0.305054)
			(stroke
				(width 0.1)
				(type default)
			)
			(layer "F.Fab")
		)
		(fp_line
			(start -0.12065 -0.305054)
			(end -0.12065 -0.2794)
			(stroke
				(width 0.1)
				(type default)
			)
			(layer "F.Fab")
		)
		(pad "1" smd circle
			(at -0.40005 0 270)
			(size 0 0)
			(layers "F.Cu" "F.Mask" "F.Paste")
			(net "SSD15_LED_ISO_N")
		)
		(pad "2" smd circle
			(at 0.40005 0 270)
			(size 0 0)
			(layers "F.Cu" "F.Mask" "F.Paste")
			(net "SSD15_LED_ISO_R_N")
		)
	)
)
